# BASEBOARD_FAB2 (Tioga Pass) — schematic netlist excerpt (pin names and nets, part order shuffled) for the footprints in the layout excerpt that follows; sources: Cadence DE-HDL packaged netlist, KiCad conversion of Wiwynn_Tioga_Pass_MB.brd

U14E2  TTL1G08  NC7SZ08 IC  pkg SOTLF  page 248
  A(0)  = RST_PCIE_M2_DEV_N
  B(0)  = RST_PCIE_M2_DEV_AND
  Y(0)  = RST_PCIE_M2_DEV_IC_N

T1P24  TPAD-DIFF-4P-GP  pkg DISCRET-GB3  page 256
  \1\  = L14_100OHM_6INCH_DP
  \2\  = L14_100OHM_6INCH_DN
  GND1  = GND
  GND2  = GND

(kicad_pcb
	(version 20260206)
	(generator "pcbnew")
	(generator_version "10.0")
	(general
		(thickness 1.6)
		(legacy_teardrops no)
	)
	(paper "A4")
	(title_block
		(title "Wiwynn_Tioga_Pass_MB.brd")
		(comment 1 "Tioga Pass / footprints 1379-1380 of 4770")
	)
	(layers
		(0 "F.Cu" signal "TOP")
		(4 "In1.Cu" signal "L2GND")
		(6 "In2.Cu" signal "L3")
		(8 "In3.Cu" signal "L4GND")
		(10 "In4.Cu" signal "L5")
		(12 "In5.Cu" signal "L6GND")
		(14 "In6.Cu" signal "L7VCC")
		(16 "In7.Cu" signal "L8VCC")
		(18 "In8.Cu" signal "L9GND")
		(20 "In9.Cu" signal "L10")
		(22 "In10.Cu" signal "L11GND")
		(24 "In11.Cu" signal "L12")
		(26 "In12.Cu" signal "L13GND")
		(2 "B.Cu" signal "BOTTOM")
		(9 "F.Adhes" user "F.Adhesive")
		(11 "B.Adhes" user "B.Adhesive")
		(13 "F.Paste" user "Package Geometry/Pastemask Top")
		(15 "B.Paste" user "Package Geometry/Pastemask Bottom")
		(5 "F.SilkS" user "Ref Des/Silkscreen Top")
		(7 "B.SilkS" user "Ref Des/Silkscreen Bottom")
		(1 "F.Mask" user "Board Geometry/Soldermask Top")
		(3 "B.Mask" user "Board Geometry/Soldermask Bottom")
		(17 "Dwgs.User" user "User.Drawings")
		(19 "Cmts.User" user "User.Comments")
		(21 "Eco1.User" user "User.Eco1")
		(23 "Eco2.User" user "User.Eco2")
		(25 "Edge.Cuts" user "Board Geometry/Outline")
		(27 "Margin" user)
		(31 "F.CrtYd" user "Package Geometry/Place Bound Top")
		(29 "B.CrtYd" user "Package Geometry/Place Bound Bottom")
		(35 "F.Fab" user "Ref Des/Assembly Top")
		(33 "B.Fab" user "Ref Des/Assembly Bottom")
	)
	(footprint ""
		(layer "F.Cu")
		(at 382.490726 -80.941926 90)
		(property "Reference" "U14E2"
			(at -0.14986 2.621788 90)
			(unlocked yes)
			(layer "F.SilkS")
			(effects
				(font
					(size 1.27 0.964946)
					(thickness 0.000001)
				)
				(justify left)
			)
		)
		(property "Value" ""
			(at 0 0 90)
			(layer "F.Fab")
			(effects
				(font
					(size 1.27 1.27)
				)
			)
		)
		(duplicate_pad_numbers_are_jumpers no)
		(fp_circle
			(center -0.4699 -0.8382)
			(end -0.4699 -0.7112)
			(stroke
				(width 0.254)
				(type default)
			)
			(fill no)
			(layer "F.SilkS")
		)
		(fp_poly
			(pts
				(xy 0.21463 -0.450088) (xy 1.56337 -0.450088) (xy 1.56337 1.75006) (xy 0.21463 1.75006)
			)
			(stroke
				(width 0)
				(type default)
			)
			(fill no)
			(layer "F.CrtYd")
		)
		(fp_line
			(start 1.56337 -0.450088)
			(end 1.56337 1.75006)
			(stroke
				(width 0.1)
				(type default)
			)
			(layer "F.Fab")
		)
		(fp_line
			(start 0.21463 -0.450088)
			(end 1.56337 -0.450088)
			(stroke
				(width 0.1)
				(type default)
			)
			(layer "F.Fab")
		)
		(fp_line
			(start 1.56337 1.75006)
			(end 0.21463 1.75006)
			(stroke
				(width 0.1)
				(type default)
			)
			(layer "F.Fab")
		)
		(fp_line
			(start 0.21463 1.75006)
			(end 0.21463 -0.450088)
			(stroke
				(width 0.1)
				(type default)
			)
			(layer "F.Fab")
		)
		(fp_circle
			(center -0.4699 -0.8382)
			(end -0.4699 -0.7112)
			(stroke
				(width 0.254)
				(type default)
			)
			(fill no)
			(layer "F.Fab")
		)
		(pad "1" smd rect
			(at 0 0 90)
			(size 1.016 0.381)
			(layers "F.Cu" "F.Mask" "F.Paste")
			(net "RST_PCIE_M2_DEV_N")
		)
		(pad "2" smd rect
			(at 0 0.649986 90)
			(size 1.016 0.381)
			(layers "F.Cu" "F.Mask" "F.Paste")
			(net "RST_PCIE_M2_DEV_AND")
		)
		(pad "3" smd rect
			(at 0 1.299972 90)
			(size 1.016 0.381)
			(layers "F.Cu" "F.Mask" "F.Paste")
			(net "GND")
		)
		(pad "4" smd rect
			(at 1.778 1.299972 90)
			(size 1.016 0.381)
			(layers "F.Cu" "F.Mask" "F.Paste")
			(net "RST_PCIE_M2_DEV_IC_N")
		)
		(pad "5" smd rect
			(at 1.778 0 90)
			(size 1.016 0.381)
			(layers "F.Cu" "F.Mask" "F.Paste")
			(net "P3V3")
		)
	)
	(footprint ""
		(layer "F.Cu")
		(at 367.603532 12.003278 -90)
		(property "Reference" "T1P24"
			(at 0 0 270)
			(layer "F.SilkS")
			(hide yes)
			(effects
				(font
					(size 1.27 1.27)
				)
			)
		)
		(property "Value" "*"
			(at -3.302 1.12395 270)
			(unlocked yes)
			(layer "F.Fab")
			(hide yes)
			(effects
				(font
					(size 0.889 0.889)
					(thickness 0.1524)
				)
			)
		)
		(property "Device Type" "TPAD-DIFF-4P-GP_DISCRET-GB3-TPA"
			(at -3.302 -0.40005 270)
			(unlocked yes)
			(layer "F.Fab")
			(hide yes)
			(effects
				(font
					(size 0.889 0.889)
					(thickness 0.1524)
				)
			)
		)
		(duplicate_pad_numbers_are_jumpers no)
		(fp_line
			(start -2.286 2.286)
			(end 2.286 2.286)
			(stroke
				(width 0.1524)
				(type default)
			)
			(layer "F.SilkS")
		)
		(fp_line
			(start 2.286 2.286)
			(end 2.286 -2.286)
			(stroke
				(width 0.1524)
				(type default)
			)
			(layer "F.SilkS")
		)
		(fp_line
			(start -2.286 -2.286)
			(end -2.286 2.286)
			(stroke
				(width 0.1524)
				(type default)
			)
			(layer "F.SilkS")
		)
		(fp_line
			(start 2.286 -2.286)
			(end -2.286 -2.286)
			(stroke
				(width 0.1524)
				(type default)
			)
			(layer "F.SilkS")
		)
		(fp_line
			(start -2.413 -2.413)
			(end -2.413 -1.143)
			(stroke
				(width 0.4064)
				(type default)
			)
			(layer "F.SilkS")
		)
		(fp_line
			(start -1.143 -2.413)
			(end -2.413 -2.413)
			(stroke
				(width 0.4064)
				(type default)
			)
			(layer "F.SilkS")
		)
		(fp_rect
			(start -2.54 2.54)
			(end 2.54 -2.54)
			(stroke
				(width 0)
				(type default)
			)
			(fill no)
			(layer "F.CrtYd")
		)
		(fp_rect
			(start -2.54 2.54)
			(end 2.54 -2.54)
			(stroke
				(width 0)
				(type default)
			)
			(fill no)
			(layer "F.Fab")
		)
		(pad "1" thru_hole circle
			(at -1.27 -1.27 270)
			(size 1.524 1.524)
			(drill 0.9144)
			(layers "*.Cu" "*.Mask")
			(remove_unused_layers no)
			(net "L14_100OHM_6INCH_DP")
			(clearance -0.0508)
			(thermal_gap 0.127)
			(padstack
				(mode front_inner_back)
				(layer "Inner"
					(shape circle)
					(size 1.1684 1.1684)
					(clearance 0.127)
				)
				(layer "B.Cu"
					(shape circle)
					(size 1.524 1.524)
					(clearance -0.0508)
				)
			)
		)
		(pad "2" thru_hole circle
			(at 1.27 -1.27 270)
			(size 1.524 1.524)
			(drill 0.9144)
			(layers "*.Cu" "*.Mask")
			(remove_unused_layers no)
			(net "L14_100OHM_6INCH_DN")
			(clearance -0.0508)
			(thermal_gap 0.127)
			(padstack
				(mode front_inner_back)
				(layer "Inner"
					(shape circle)
					(size 1.1684 1.1684)
					(clearance 0.127)
				)
				(layer "B.Cu"
					(shape circle)
					(size 1.524 1.524)
					(clearance -0.0508)
				)
			)
		)
		(pad "GND1" thru_hole rect
			(at -1.27 1.27 270)
			(size 1.524 1.524)
			(drill 0.9144)
			(layers "*.Cu" "*.Mask")
			(remove_unused_layers no)
			(net "GND")
			(clearance -0.0508)
			(thermal_gap 0.127)
			(padstack
				(mode front_inner_back)
				(layer "Inner"
					(shape circle)
					(size 1.1684 1.1684)
					(clearance 0.127)
				)
				(layer "B.Cu"
					(shape rect)
					(size 1.524 1.524)
					(clearance -0.0508)
				)
			)
		)
		(pad "GND2" thru_hole rect
			(at 1.27 1.27 270)
			(size 1.524 1.524)
			(drill 0.9144)
			(layers "*.Cu" "*.Mask")
			(remove_unused_layers no)
			(net "GND")
			(clearance -0.0508)
			(thermal_gap 0.127)
			(padstack
				(mode front_inner_back)
				(layer "Inner"
					(shape circle)
					(size 1.1684 1.1684)
					(clearance 0.127)
				)
				(layer "B.Cu"
					(shape rect)
					(size 1.524 1.524)
					(clearance -0.0508)
				)
			)
		)
	)
)
